# TIMECARD (Time Appliance Project (Time Card)) — schematic netlist excerpt (pin names and nets, part order shuffled) for the footprints in the layout excerpt that follows; sources: Cadence DE-HDL packaged netlist, KiCad conversion of R4006-B0001-02_R01.brd

U11  TS3USB3031RMGR_WQFN12  TS3USB3031RMGR  pkg QFN12_071_P0157  page 21
  SEL0  = XP5R0V_USB_CONN_DET
  SEL1  = UNNAMED_527_RESISTOR_I126_1
  USB1_P  = MAC_USB_DP
  USB1_N  = MAC_USB_DM
  USB2_P  = CONN_MICRO_USB_DP
  USB2_N  = CONN_MICRO_USB_DM
  MHL_P  = NC
  MHL_N  = NC
  GND  = SG
  D_N  = MUX_USB_DM
  D_P  = MUX_USB_DP
  VCC  = XP3R3V_FPGA

(kicad_pcb
	(version 20260206)
	(generator "pcbnew")
	(generator_version "10.0")
	(general
		(thickness 1.6)
		(legacy_teardrops no)
	)
	(paper "A4")
	(title_block
		(title "timecard-production-celestica-r4006 — R4006-B0001-02_R01.brd")
		(comment 1 "Time Appliance Project (Time Card) / footprints 298-298 of 1113")
	)
	(layers
		(0 "F.Cu" signal "TOP")
		(4 "In1.Cu" signal "L02_GND1")
		(6 "In2.Cu" signal "L03_SIG1")
		(8 "In3.Cu" signal "L04_GND2")
		(10 "In4.Cu" signal "L05_VCC1")
		(12 "In5.Cu" signal "L06_VCC2")
		(14 "In6.Cu" signal "L07_GND3")
		(16 "In7.Cu" signal "L08_SIG2")
		(18 "In8.Cu" signal "L09_GND4")
		(2 "B.Cu" signal "BOTTOM")
		(9 "F.Adhes" user "F.Adhesive")
		(11 "B.Adhes" user "B.Adhesive")
		(13 "F.Paste" user "Package Geometry/Pastemask Top")
		(15 "B.Paste" user "Package Geometry/Pastemask Bottom")
		(5 "F.SilkS" user "Ref Des/Silkscreen Top")
		(7 "B.SilkS" user "Ref Des/Silkscreen Bottom")
		(1 "F.Mask" user "Board Geometry/Soldermask Top")
		(3 "B.Mask" user "Board Geometry/Soldermask Bottom")
		(17 "Dwgs.User" user "User.Drawings")
		(19 "Cmts.User" user "User.Comments")
		(21 "Eco1.User" user "User.Eco1")
		(23 "Eco2.User" user "User.Eco2")
		(25 "Edge.Cuts" user "Board Geometry/Outline")
		(27 "Margin" user)
		(31 "F.CrtYd" user "Package Geometry/Place Bound Top")
		(29 "B.CrtYd" user "Package Geometry/Place Bound Bottom")
		(35 "F.Fab" user "Ref Des/Assembly Top")
		(33 "B.Fab" user "Ref Des/Assembly Bottom")
	)
	(footprint ""
		(layer "F.Cu")
		(at 90.017854 -48.653446 90)
		(property "Reference" "U11"
			(at 2.754884 3.581146 0)
			(unlocked yes)
			(layer "F.SilkS")
			(effects
				(font
					(size 0.7874 0.5842)
					(thickness 0.1524)
				)
			)
		)
		(property "Value" ""
			(at 0 0 90)
			(layer "F.Fab")
			(effects
				(font
					(size 1.27 1.27)
				)
			)
		)
		(property "Device Type" "TS3USB3031RMGR_WQFN12-G220-103A"
			(at 0 3.481324 90)
			(unlocked yes)
			(layer "F.Fab")
			(hide yes)
			(effects
				(font
					(size 0.7874 0.5842)
					(thickness 0.1524)
				)
			)
		)
		(property "User Part Number" "PARTNUM*"
			(at 0 4.675124 90)
			(unlocked yes)
			(layer "Cmts.User")
			(hide yes)
			(effects
				(font
					(size 0.7874 0.5842)
					(thickness 0.1524)
				)
			)
		)
		(duplicate_pad_numbers_are_jumpers no)
		(fp_line
			(start 1.690624 -1.690624)
			(end -1.690624 -1.690624)
			(stroke
				(width 0.1)
				(type default)
			)
			(layer "F.SilkS")
		)
		(fp_line
			(start -1.690624 -1.690624)
			(end -1.690624 1.690624)
			(stroke
				(width 0.1)
				(type default)
			)
			(layer "F.SilkS")
		)
		(fp_line
			(start 1.690624 1.690624)
			(end 1.690624 -1.690624)
			(stroke
				(width 0.1)
				(type default)
			)
			(layer "F.SilkS")
		)
		(fp_line
			(start -1.690624 1.690624)
			(end 1.690624 1.690624)
			(stroke
				(width 0.1)
				(type default)
			)
			(layer "F.SilkS")
		)
		(fp_poly
			(pts
				(arc
					(start -2.368296 -0.184658)
					(mid -2.368296 -0.946658)
					(end -2.368296 -0.184658)
				)
			)
			(stroke
				(width 0)
				(type default)
			)
			(fill yes)
			(layer "F.SilkS")
		)
		(fp_rect
			(start -1.944624 -1.944624)
			(end 1.944624 1.944624)
			(stroke
				(width 0)
				(type default)
			)
			(fill no)
			(layer "F.CrtYd")
		)
		(fp_line
			(start 0.94996 -0.94996)
			(end -0.94996 -0.94996)
			(stroke
				(width 0.1)
				(type default)
			)
			(layer "F.Fab")
		)
		(fp_line
			(start -0.94996 -0.94996)
			(end -0.94996 0.94996)
			(stroke
				(width 0.1)
				(type default)
			)
			(layer "F.Fab")
		)
		(fp_line
			(start 0.94996 0.94996)
			(end 0.94996 -0.94996)
			(stroke
				(width 0.1)
				(type default)
			)
			(layer "F.Fab")
		)
		(fp_line
			(start -0.94996 0.94996)
			(end 0.94996 0.94996)
			(stroke
				(width 0.1)
				(type default)
			)
			(layer "F.Fab")
		)
		(fp_poly
			(pts
				(arc
					(start -1.733296 -0.438658)
					(mid -1.733296 -1.200658)
					(end -1.733296 -0.438658)
				)
			)
			(stroke
				(width 0)
				(type default)
			)
			(fill yes)
			(layer "F.Fab")
		)
		(fp_text user "8"
			(at 2.1844 -0.455168 90)
			(unlocked yes)
			(layer "F.SilkS")
			(effects
				(font
					(size 0.635 0.4064)
					(thickness 0.1524)
				)
			)
		)
		(fp_text user "2"
			(at -2.203196 0.533146 0)
			(unlocked yes)
			(layer "F.SilkS")
			(effects
				(font
					(size 0.635 0.4064)
					(thickness 0.1524)
				)
			)
		)
		(fp_text user "7"
			(at 2.207006 0.53848 90)
			(unlocked yes)
			(layer "F.SilkS")
			(effects
				(font
					(size 0.635 0.4064)
					(thickness 0.1524)
				)
			)
		)
		(fp_text user "3"
			(at -1.390396 2.057146 0)
			(unlocked yes)
			(layer "F.SilkS")
			(effects
				(font
					(size 0.635 0.4064)
					(thickness 0.1524)
				)
			)
		)
		(fp_text user "6"
			(at 1.479804 2.692146 0)
			(unlocked yes)
			(layer "F.SilkS")
			(effects
				(font
					(size 0.635 0.4064)
					(thickness 0.1524)
				)
			)
		)
		(fp_text user "12"
			(at -0.674116 -2.006854 0)
			(unlocked yes)
			(layer "F.Fab")
			(effects
				(font
					(size 0.7874 0.5842)
					(thickness 0.1524)
				)
			)
		)
		(fp_text user "9"
			(at 0.722884 -1.752854 0)
			(unlocked yes)
			(layer "F.Fab")
			(effects
				(font
					(size 0.7874 0.5842)
					(thickness 0.1524)
				)
			)
		)
		(fp_text user "8"
			(at 1.77673 -0.677418 0)
			(unlocked yes)
			(layer "F.Fab")
			(effects
				(font
					(size 0.7874 0.5842)
					(thickness 0.1524)
				)
			)
		)
		(fp_text user "7"
			(at 1.798828 0.316484 0)
			(unlocked yes)
			(layer "F.Fab")
			(effects
				(font
					(size 0.7874 0.5842)
					(thickness 0.1524)
				)
			)
		)
		(fp_text user "2"
			(at -1.563116 0.914146 0)
			(unlocked yes)
			(layer "F.Fab")
			(effects
				(font
					(size 0.7874 0.5842)
					(thickness 0.1524)
				)
			)
		)
		(fp_text user "6"
			(at 1.103884 1.549146 0)
			(unlocked yes)
			(layer "F.Fab")
			(effects
				(font
					(size 0.7874 0.5842)
					(thickness 0.1524)
				)
			)
		)
		(fp_text user "3"
			(at -0.420116 1.549146 0)
			(unlocked yes)
			(layer "F.Fab")
			(effects
				(font
					(size 0.7874 0.5842)
					(thickness 0.1524)
				)
			)
		)
		(pad "1" smd rect
			(at -0.763524 -0.199898 90)
			(size 1.3462 0.2032)
			(layers "F.Cu" "F.Mask" "F.Paste")
			(net "XP5R0V_USB_CONN_DET")
		)
		(pad "2" smd rect
			(at -0.763524 0.200152 90)
			(size 1.3462 0.2032)
			(layers "F.Cu" "F.Mask" "F.Paste")
			(net "UNNAMED_527_RESISTOR_I126_1")
		)
		(pad "3" smd rect
			(at -0.599948 0.966724 90)
			(size 0.2032 0.9398)
			(layers "F.Cu" "F.Mask" "F.Paste")
			(net "MAC_USB_DP")
		)
		(pad "4" smd rect
			(at -0.199898 0.966724 90)
			(size 0.2032 0.9398)
			(layers "F.Cu" "F.Mask" "F.Paste")
			(net "MAC_USB_DM")
		)
		(pad "5" smd rect
			(at 0.199898 0.966724 90)
			(size 0.2032 0.9398)
			(layers "F.Cu" "F.Mask" "F.Paste")
			(net "CONN_MICRO_USB_DP")
		)
		(pad "6" smd rect
			(at 0.599948 0.966724 90)
			(size 0.2032 0.9398)
			(layers "F.Cu" "F.Mask" "F.Paste")
			(net "CONN_MICRO_USB_DM")
		)
		(pad "7" smd rect
			(at 0.763524 0.200152 90)
			(size 1.3462 0.2032)
			(layers "F.Cu" "F.Mask" "F.Paste")
			(net "Net_759")
		)
		(pad "8" smd rect
			(at 0.763524 -0.199898 90)
			(size 1.3462 0.2032)
			(layers "F.Cu" "F.Mask" "F.Paste")
			(net "Net_760")
		)
		(pad "9" smd rect
			(at 0.599948 -0.966724 90)
			(size 0.2032 0.9398)
			(layers "F.Cu" "F.Mask" "F.Paste")
			(net "SG")
		)
		(pad "10" smd rect
			(at 0.199898 -0.966724 90)
			(size 0.2032 0.9398)
			(layers "F.Cu" "F.Mask" "F.Paste")
			(net "MUX_USB_DM")
		)
		(pad "11" smd rect
			(at -0.199898 -0.966724 90)
			(size 0.2032 0.9398)
			(layers "F.Cu" "F.Mask" "F.Paste")
			(net "MUX_USB_DP")
		)
		(pad "12" smd rect
			(at -0.599948 -0.966724 90)
			(size 0.2032 0.9398)
			(layers "F.Cu" "F.Mask" "F.Paste")
			(net "XP3R3V_FPGA")
		)
	)
)
